# ZAIUS-MB-EVT3-HW-EBOM-X00_20161228-add_2nd_source_X15-20170106-Final.xls — Component Qual Tracker (bom)
|  |  |  |  |  |  |  |  | Part to be included on following build: |  |  |  |  |  |
| Item No. | Part Group | Single/Sole/Multi | Item Description | ODM P/N | Customer PN | Vendor | Vendor P/N | X00 Build | X01 Build | X02 Build | Qual Build | Qualification Target Date | Qualification Complete Date |
|  | VR Controllers |  |  |  |  | Vendor #1 |  |  |  |  |  |  |  |
|  |  |  |  |  |  | Vendor #2 |  |  |  |  |  |  |  |
|  | FETS |  |  |  |  | Vendor #1 |  |  |  |  |  |  |  |
|  |  |  |  |  |  | Vendor #2 |  |  |  |  |  |  |  |
|  | INDUCTORS |  |  |  |  | Vendor #1 |  |  |  |  |  |  |  |
|  |  |  |  |  |  | Vendor #2 |  |  |  |  |  |  |  |
|  | VREG CAPS |  |  |  |  | Vendor #1 |  |  |  |  |  |  |  |
|  |  |  |  |  |  | Vendor #2 |  |  |  |  |  |  |  |
|  | CRYSTALS |  |  |  |  | Vendor #1 |  |  |  |  |  |  |  |
|  |  |  |  |  |  | Vendor #2 |  |  |  |  |  |  |  |
|  | CONNECTORS |  |  |  |  | Vendor #1 |  |  |  |  |  |  |  |
|  |  |  |  |  |  | Vendor #2 |  |  |  |  |  |  |  |
|  | IC'S |  |  |  |  | Vendor #1 |  |  |  |  |  |  |  |
|  |  |  |  |  |  | Vendor #2 |  |  |  |  |  |  |  |
|  | MISC. |  |  |  |  | Vendor #1 |  |  |  |  |  |  |  |
|  | (HEATSINKS) |  |  |  |  | Vendor #2 |  |  |  |  |  |  |  |
